(kicad_pcb
	(version 20260206)
	(generator "pcbnew")
	(generator_version "10.0")
	(general
		(thickness 1.6)
		(legacy_teardrops no)
	)
	(paper "A4")
	(title_block
		(title "pdpb — Lightning_PDPB_BRD.brd")
		(comment 1 "Lightning (Wiwynn / Facebook NVMe JBOF) / footprints 130-136 of 1140")
	)
	(layers
		(0 "F.Cu" signal "TOP")
		(4 "In1.Cu" signal "L2GND")
		(6 "In2.Cu" signal "L3")
		(8 "In3.Cu" signal "L4VCC")
		(10 "In4.Cu" signal "L5VCC")
		(12 "In5.Cu" signal "L6")
		(14 "In6.Cu" signal "L7GND")
		(2 "B.Cu" signal "BOTTOM")
		(9 "F.Adhes" user "F.Adhesive")
		(11 "B.Adhes" user "B.Adhesive")
		(13 "F.Paste" user "Package Geometry/Pastemask Top")
		(15 "B.Paste" user "Package Geometry/Pastemask Bottom")
		(5 "F.SilkS" user "Ref Des/Silkscreen Top")
		(7 "B.SilkS" user "Ref Des/Silkscreen Bottom")
		(1 "F.Mask" user "Board Geometry/Soldermask Top")
		(3 "B.Mask" user "Board Geometry/Soldermask Bottom")
		(17 "Dwgs.User" user "User.Drawings")
		(19 "Cmts.User" user "User.Comments")
		(21 "Eco1.User" user "User.Eco1")
		(23 "Eco2.User" user "User.Eco2")
		(25 "Edge.Cuts" user "Board Geometry/Outline")
		(27 "Margin" user)
		(31 "F.CrtYd" user "Package Geometry/Place Bound Top")
		(29 "B.CrtYd" user "Package Geometry/Place Bound Bottom")
		(35 "F.Fab" user "Ref Des/Assembly Top")
		(33 "B.Fab" user "Ref Des/Assembly Bottom")
	)
	(footprint ""
		(layer "F.Cu")
		(at 96.52 -219.456 180)
		(property "Reference" "R9094"
			(at 0 0 180)
			(layer "F.SilkS")
			(hide yes)
			(effects
				(font
					(size 1.27 1.27)
				)
			)
		)
		(property "Value" "27R2F-GP"
			(at 0.064008 -3.993896 180)
			(unlocked yes)
			(layer "F.Fab")
			(hide yes)
			(effects
				(font
					(size 1.016 1.016)
					(thickness 0.1524)
				)
			)
		)
		(property "Device Type" "R402H16"
			(at 0.064008 -5.517896 180)
			(unlocked yes)
			(layer "F.Fab")
			(hide yes)
			(effects
				(font
					(size 1.016 1.016)
					(thickness 0.1524)
				)
			)
		)
		(duplicate_pad_numbers_are_jumpers no)
		(fp_line
			(start 0.508 -0.9398)
			(end -0.508 -0.9398)
			(stroke
				(width 0.1524)
				(type default)
			)
			(layer "F.SilkS")
		)
		(fp_line
			(start -0.508 -0.9398)
			(end -0.508 0.9398)
			(stroke
				(width 0.1524)
				(type default)
			)
			(layer "F.SilkS")
		)
		(fp_rect
			(start -0.508 0.9398)
			(end 0.508 -0.9398)
			(stroke
				(width 0)
				(type default)
			)
			(fill no)
			(layer "F.CrtYd")
		)
		(fp_rect
			(start -0.508 0.9398)
			(end 0.508 -0.9398)
			(stroke
				(width 0)
				(type default)
			)
			(fill no)
			(layer "F.Fab")
		)
		(pad "1" smd custom
			(at 0 -0.4445 180)
			(size 0.1397 0.1397)
			(layers "F.Cu" "F.Mask" "F.Paste")
			(net "PE_CLK_100M_DR7_1_R_P")
			(options
				(clearance outline)
				(anchor circle)
			)
			(primitives
				(gr_poly
					(pts
						(arc
							(start -0.1778 -0.2794)
							(mid -0.249642 -0.249642)
							(end -0.2794 -0.1778)
						)
						(arc
							(start -0.2794 0.1778)
							(mid -0.249642 0.249642)
							(end -0.1778 0.2794)
						)
						(arc
							(start 0.1778 0.2794)
							(mid 0.249642 0.249642)
							(end 0.2794 0.1778)
						)
						(arc
							(start 0.2794 -0.1778)
							(mid 0.249642 -0.249642)
							(end 0.1778 -0.2794)
						)
					)
					(width 0)
					(fill yes)
				)
			)
		)
		(pad "2" smd custom
			(at 0 0.4445 180)
			(size 0.1397 0.1397)
			(layers "F.Cu" "F.Mask" "F.Paste")
			(net "PE_CLK100M_DR7_1_P")
			(options
				(clearance outline)
				(anchor circle)
			)
			(primitives
				(gr_poly
					(pts
						(arc
							(start -0.1778 -0.2794)
							(mid -0.249642 -0.249642)
							(end -0.2794 -0.1778)
						)
						(arc
							(start -0.2794 0.1778)
							(mid -0.249642 0.249642)
							(end -0.1778 0.2794)
						)
						(arc
							(start 0.1778 0.2794)
							(mid 0.249642 0.249642)
							(end 0.2794 0.1778)
						)
						(arc
							(start 0.2794 -0.1778)
							(mid 0.249642 -0.249642)
							(end 0.1778 -0.2794)
						)
					)
					(width 0)
					(fill yes)
				)
			)
		)
	)
	(footprint ""
		(layer "F.Cu")
		(at 242.062 -423.799 90)
		(property "Reference" "PR9060"
			(at 0 0 90)
			(layer "F.SilkS")
			(hide yes)
			(effects
				(font
					(size 1.27 1.27)
				)
			)
		)
		(property "Value" "0R2J-2-GP"
			(at 0.064008 -3.993896 90)
			(unlocked yes)
			(layer "F.Fab")
			(hide yes)
			(effects
				(font
					(size 1.016 1.016)
					(thickness 0.1524)
				)
			)
		)
		(property "Device Type" "R402H16"
			(at 0.064008 -5.517896 90)
			(unlocked yes)
			(layer "F.Fab")
			(hide yes)
			(effects
				(font
					(size 1.016 1.016)
					(thickness 0.1524)
				)
			)
		)
		(duplicate_pad_numbers_are_jumpers no)
		(fp_line
			(start 0.508 -0.9398)
			(end -0.508 -0.9398)
			(stroke
				(width 0.1524)
				(type default)
			)
			(layer "F.SilkS")
		)
		(fp_line
			(start -0.508 -0.9398)
			(end -0.508 0.9398)
			(stroke
				(width 0.1524)
				(type default)
			)
			(layer "F.SilkS")
		)
		(fp_rect
			(start -0.508 0.9398)
			(end 0.508 -0.9398)
			(stroke
				(width 0)
				(type default)
			)
			(fill no)
			(layer "F.CrtYd")
		)
		(fp_rect
			(start -0.508 0.9398)
			(end 0.508 -0.9398)
			(stroke
				(width 0)
				(type default)
			)
			(fill no)
			(layer "F.Fab")
		)
		(pad "1" smd custom
			(at 0 -0.4445 90)
			(size 0.1397 0.1397)
			(layers "F.Cu" "F.Mask" "F.Paste")
			(net "SAS_I2C_C_BUF_SCL_R")
			(options
				(clearance outline)
				(anchor circle)
			)
			(primitives
				(gr_poly
					(pts
						(arc
							(start -0.1778 -0.2794)
							(mid -0.249642 -0.249642)
							(end -0.2794 -0.1778)
						)
						(arc
							(start -0.2794 0.1778)
							(mid -0.249642 0.249642)
							(end -0.1778 0.2794)
						)
						(arc
							(start 0.1778 0.2794)
							(mid 0.249642 0.249642)
							(end 0.2794 0.1778)
						)
						(arc
							(start 0.2794 -0.1778)
							(mid 0.249642 -0.249642)
							(end 0.1778 -0.2794)
						)
					)
					(width 0)
					(fill yes)
				)
			)
		)
		(pad "2" smd custom
			(at 0 0.4445 90)
			(size 0.1397 0.1397)
			(layers "F.Cu" "F.Mask" "F.Paste")
			(net "I2C_C_SCL")
			(options
				(clearance outline)
				(anchor circle)
			)
			(primitives
				(gr_poly
					(pts
						(arc
							(start -0.1778 -0.2794)
							(mid -0.249642 -0.249642)
							(end -0.2794 -0.1778)
						)
						(arc
							(start -0.2794 0.1778)
							(mid -0.249642 0.249642)
							(end -0.1778 0.2794)
						)
						(arc
							(start 0.1778 0.2794)
							(mid 0.249642 0.249642)
							(end 0.2794 0.1778)
						)
						(arc
							(start 0.2794 -0.1778)
							(mid 0.249642 -0.249642)
							(end 0.1778 -0.2794)
						)
					)
					(width 0)
					(fill yes)
				)
			)
		)
	)
	(footprint ""
		(layer "F.Cu")
		(at 87.503 -219.456 180)
		(property "Reference" "R9090"
			(at 0 0 180)
			(layer "F.SilkS")
			(hide yes)
			(effects
				(font
					(size 1.27 1.27)
				)
			)
		)
		(property "Value" "27R2F-GP"
			(at 0.064008 -3.993896 180)
			(unlocked yes)
			(layer "F.Fab")
			(hide yes)
			(effects
				(font
					(size 1.016 1.016)
					(thickness 0.1524)
				)
			)
		)
		(property "Device Type" "R402H16"
			(at 0.064008 -5.517896 180)
			(unlocked yes)
			(layer "F.Fab")
			(hide yes)
			(effects
				(font
					(size 1.016 1.016)
					(thickness 0.1524)
				)
			)
		)
		(duplicate_pad_numbers_are_jumpers no)
		(fp_line
			(start 0.508 -0.9398)
			(end -0.508 -0.9398)
			(stroke
				(width 0.1524)
				(type default)
			)
			(layer "F.SilkS")
		)
		(fp_line
			(start -0.508 -0.9398)
			(end -0.508 0.9398)
			(stroke
				(width 0.1524)
				(type default)
			)
			(layer "F.SilkS")
		)
		(fp_rect
			(start -0.508 0.9398)
			(end 0.508 -0.9398)
			(stroke
				(width 0)
				(type default)
			)
			(fill no)
			(layer "F.CrtYd")
		)
		(fp_rect
			(start -0.508 0.9398)
			(end 0.508 -0.9398)
			(stroke
				(width 0)
				(type default)
			)
			(fill no)
			(layer "F.Fab")
		)
		(pad "1" smd custom
			(at 0 -0.4445 180)
			(size 0.1397 0.1397)
			(layers "F.Cu" "F.Mask" "F.Paste")
			(net "PE_CLK_100M_DR12_1_R_P")
			(options
				(clearance outline)
				(anchor circle)
			)
			(primitives
				(gr_poly
					(pts
						(arc
							(start -0.1778 -0.2794)
							(mid -0.249642 -0.249642)
							(end -0.2794 -0.1778)
						)
						(arc
							(start -0.2794 0.1778)
							(mid -0.249642 0.249642)
							(end -0.1778 0.2794)
						)
						(arc
							(start 0.1778 0.2794)
							(mid 0.249642 0.249642)
							(end 0.2794 0.1778)
						)
						(arc
							(start 0.2794 -0.1778)
							(mid 0.249642 -0.249642)
							(end 0.1778 -0.2794)
						)
					)
					(width 0)
					(fill yes)
				)
			)
		)
		(pad "2" smd custom
			(at 0 0.4445 180)
			(size 0.1397 0.1397)
			(layers "F.Cu" "F.Mask" "F.Paste")
			(net "PE_CLK100M_DR12_1_P")
			(options
				(clearance outline)
				(anchor circle)
			)
			(primitives
				(gr_poly
					(pts
						(arc
							(start -0.1778 -0.2794)
							(mid -0.249642 -0.249642)
							(end -0.2794 -0.1778)
						)
						(arc
							(start -0.2794 0.1778)
							(mid -0.249642 0.249642)
							(end -0.1778 0.2794)
						)
						(arc
							(start 0.1778 0.2794)
							(mid 0.249642 0.249642)
							(end 0.2794 0.1778)
						)
						(arc
							(start 0.2794 -0.1778)
							(mid 0.249642 -0.249642)
							(end 0.1778 -0.2794)
						)
					)
					(width 0)
					(fill yes)
				)
			)
		)
	)
	(footprint ""
		(layer "F.Cu")
		(at 90.17 -115.062)
		(property "Reference" "R9614"
			(at 0 0 0)
			(layer "F.SilkS")
			(hide yes)
			(effects
				(font
					(size 1.27 1.27)
				)
			)
		)
		(property "Value" "10R2F-L-GP"
			(at 0.064008 -3.993896 0)
			(unlocked yes)
			(layer "F.Fab")
			(hide yes)
			(effects
				(font
					(size 1.016 1.016)
					(thickness 0.1524)
				)
			)
		)
		(property "Device Type" "R402H14"
			(at 0.064008 -5.517896 0)
			(unlocked yes)
			(layer "F.Fab")
			(hide yes)
			(effects
				(font
					(size 1.016 1.016)
					(thickness 0.1524)
				)
			)
		)
		(duplicate_pad_numbers_are_jumpers no)
		(fp_line
			(start -0.508 -0.9398)
			(end -0.508 0.9398)
			(stroke
				(width 0.1524)
				(type default)
			)
			(layer "F.SilkS")
		)
		(fp_line
			(start 0.508 -0.9398)
			(end -0.508 -0.9398)
			(stroke
				(width 0.1524)
				(type default)
			)
			(layer "F.SilkS")
		)
		(fp_rect
			(start -0.508 0.9398)
			(end 0.508 -0.9398)
			(stroke
				(width 0)
				(type default)
			)
			(fill no)
			(layer "F.CrtYd")
		)
		(fp_rect
			(start -0.508 0.9398)
			(end 0.508 -0.9398)
			(stroke
				(width 0)
				(type default)
			)
			(fill no)
			(layer "F.Fab")
		)
		(pad "1" smd custom
			(at 0 -0.4445)
			(size 0.1397 0.1397)
			(layers "F.Cu" "F.Mask" "F.Paste")
			(net "SSD_PRSNT_NET13")
			(options
				(clearance outline)
				(anchor circle)
			)
			(primitives
				(gr_poly
					(pts
						(arc
							(start -0.1778 -0.2794)
							(mid -0.249642 -0.249642)
							(end -0.2794 -0.1778)
						)
						(arc
							(start -0.2794 0.1778)
							(mid -0.249642 0.249642)
							(end -0.1778 0.2794)
						)
						(arc
							(start 0.1778 0.2794)
							(mid 0.249642 0.249642)
							(end 0.2794 0.1778)
						)
						(arc
							(start 0.2794 -0.1778)
							(mid 0.249642 -0.249642)
							(end 0.1778 -0.2794)
						)
					)
					(width 0)
					(fill yes)
				)
			)
		)
		(pad "2" smd custom
			(at 0 0.4445)
			(size 0.1397 0.1397)
			(layers "F.Cu" "F.Mask" "F.Paste")
			(net "SSD_PRSNT13")
			(options
				(clearance outline)
				(anchor circle)
			)
			(primitives
				(gr_poly
					(pts
						(arc
							(start -0.1778 -0.2794)
							(mid -0.249642 -0.249642)
							(end -0.2794 -0.1778)
						)
						(arc
							(start -0.2794 0.1778)
							(mid -0.249642 0.249642)
							(end -0.1778 0.2794)
						)
						(arc
							(start 0.1778 0.2794)
							(mid 0.249642 0.249642)
							(end 0.2794 0.1778)
						)
						(arc
							(start 0.2794 -0.1778)
							(mid 0.249642 -0.249642)
							(end 0.1778 -0.2794)
						)
					)
					(width 0)
					(fill yes)
				)
			)
		)
	)
	(footprint ""
		(layer "F.Cu")
		(at 39.2176 -418.8714 180)
		(property "Reference" "R561"
			(at 0 0 180)
			(layer "F.SilkS")
			(hide yes)
			(effects
				(font
					(size 1.27 1.27)
				)
			)
		)
		(property "Value" "200KR2F-L-GP"
			(at 0.064008 -3.993896 180)
			(unlocked yes)
			(layer "F.Fab")
			(hide yes)
			(effects
				(font
					(size 1.016 1.016)
					(thickness 0.1524)
				)
			)
		)
		(property "Device Type" "R402H16"
			(at 0.064008 -5.517896 180)
			(unlocked yes)
			(layer "F.Fab")
			(hide yes)
			(effects
				(font
					(size 1.016 1.016)
					(thickness 0.1524)
				)
			)
		)
		(duplicate_pad_numbers_are_jumpers no)
		(fp_line
			(start 0.508 -0.9398)
			(end -0.508 -0.9398)
			(stroke
				(width 0.1524)
				(type default)
			)
			(layer "F.SilkS")
		)
		(fp_line
			(start -0.508 -0.9398)
			(end -0.508 0.9398)
			(stroke
				(width 0.1524)
				(type default)
			)
			(layer "F.SilkS")
		)
		(fp_rect
			(start -0.508 0.9398)
			(end 0.508 -0.9398)
			(stroke
				(width 0)
				(type default)
			)
			(fill no)
			(layer "F.CrtYd")
		)
		(fp_rect
			(start -0.508 0.9398)
			(end 0.508 -0.9398)
			(stroke
				(width 0)
				(type default)
			)
			(fill no)
			(layer "F.Fab")
		)
		(pad "1" smd custom
			(at 0 -0.4445 180)
			(size 0.1397 0.1397)
			(layers "F.Cu" "F.Mask" "F.Paste")
			(net "SW_SSD10_R")
			(options
				(clearance outline)
				(anchor circle)
			)
			(primitives
				(gr_poly
					(pts
						(arc
							(start -0.1778 -0.2794)
							(mid -0.249642 -0.249642)
							(end -0.2794 -0.1778)
						)
						(arc
							(start -0.2794 0.1778)
							(mid -0.249642 0.249642)
							(end -0.1778 0.2794)
						)
						(arc
							(start 0.1778 0.2794)
							(mid 0.249642 0.249642)
							(end 0.2794 0.1778)
						)
						(arc
							(start 0.2794 -0.1778)
							(mid 0.249642 -0.249642)
							(end 0.1778 -0.2794)
						)
					)
					(width 0)
					(fill yes)
				)
			)
		)
		(pad "2" smd custom
			(at 0 0.4445 180)
			(size 0.1397 0.1397)
			(layers "F.Cu" "F.Mask" "F.Paste")
			(net "SW_SSD10_N")
			(options
				(clearance outline)
				(anchor circle)
			)
			(primitives
				(gr_poly
					(pts
						(arc
							(start -0.1778 -0.2794)
							(mid -0.249642 -0.249642)
							(end -0.2794 -0.1778)
						)
						(arc
							(start -0.2794 0.1778)
							(mid -0.249642 0.249642)
							(end -0.1778 0.2794)
						)
						(arc
							(start 0.1778 0.2794)
							(mid 0.249642 0.249642)
							(end 0.2794 0.1778)
						)
						(arc
							(start 0.2794 -0.1778)
							(mid 0.249642 -0.249642)
							(end 0.1778 -0.2794)
						)
					)
					(width 0)
					(fill yes)
				)
			)
		)
	)
	(footprint ""
		(layer "F.Cu")
		(at 70.231 -435.864 180)
		(property "Reference" "PR9057"
			(at 0 0 180)
			(layer "F.SilkS")
			(hide yes)
			(effects
				(font
					(size 1.27 1.27)
				)
			)
		)
		(property "Value" "0R2J-2-GP"
			(at 0.064008 -3.993896 180)
			(unlocked yes)
			(layer "F.Fab")
			(hide yes)
			(effects
				(font
					(size 1.016 1.016)
					(thickness 0.1524)
				)
			)
		)
		(property "Device Type" "R402H16"
			(at 0.064008 -5.517896 180)
			(unlocked yes)
			(layer "F.Fab")
			(hide yes)
			(effects
				(font
					(size 1.016 1.016)
					(thickness 0.1524)
				)
			)
		)
		(duplicate_pad_numbers_are_jumpers no)
		(fp_line
			(start 0.508 -0.9398)
			(end -0.508 -0.9398)
			(stroke
				(width 0.1524)
				(type default)
			)
			(layer "F.SilkS")
		)
		(fp_line
			(start -0.508 -0.9398)
			(end -0.508 0.9398)
			(stroke
				(width 0.1524)
				(type default)
			)
			(layer "F.SilkS")
		)
		(fp_rect
			(start -0.508 0.9398)
			(end 0.508 -0.9398)
			(stroke
				(width 0)
				(type default)
			)
			(fill no)
			(layer "F.CrtYd")
		)
		(fp_rect
			(start -0.508 0.9398)
			(end 0.508 -0.9398)
			(stroke
				(width 0)
				(type default)
			)
			(fill no)
			(layer "F.Fab")
		)
		(pad "1" smd custom
			(at 0 -0.4445 180)
			(size 0.1397 0.1397)
			(layers "F.Cu" "F.Mask" "F.Paste")
			(net "SAS_I2C_B_BUF_SCL_R")
			(options
				(clearance outline)
				(anchor circle)
			)
			(primitives
				(gr_poly
					(pts
						(arc
							(start -0.1778 -0.2794)
							(mid -0.249642 -0.249642)
							(end -0.2794 -0.1778)
						)
						(arc
							(start -0.2794 0.1778)
							(mid -0.249642 0.249642)
							(end -0.1778 0.2794)
						)
						(arc
							(start 0.1778 0.2794)
							(mid 0.249642 0.249642)
							(end 0.2794 0.1778)
						)
						(arc
							(start 0.2794 -0.1778)
							(mid 0.249642 -0.249642)
							(end 0.1778 -0.2794)
						)
					)
					(width 0)
					(fill yes)
				)
			)
		)
		(pad "2" smd custom
			(at 0 0.4445 180)
			(size 0.1397 0.1397)
			(layers "F.Cu" "F.Mask" "F.Paste")
			(net "I2C_B_SCL")
			(options
				(clearance outline)
				(anchor circle)
			)
			(primitives
				(gr_poly
					(pts
						(arc
							(start -0.1778 -0.2794)
							(mid -0.249642 -0.249642)
							(end -0.2794 -0.1778)
						)
						(arc
							(start -0.2794 0.1778)
							(mid -0.249642 0.249642)
							(end -0.1778 0.2794)
						)
						(arc
							(start 0.1778 0.2794)
							(mid 0.249642 0.249642)
							(end 0.2794 0.1778)
						)
						(arc
							(start 0.2794 -0.1778)
							(mid 0.249642 -0.249642)
							(end 0.1778 -0.2794)
						)
					)
					(width 0)
					(fill yes)
				)
			)
		)
	)
	(footprint ""
		(layer "F.Cu")
		(at 221.615 -62.992)
		(property "Reference" "PC1204"
			(at 0 0 0)
			(layer "F.SilkS")
			(hide yes)
			(effects
				(font
					(size 1.27 1.27)
				)
			)
		)
		(property "Value" "SCD1U25V3KX-GP"
			(at 0 -2.8194 0)
			(unlocked yes)
			(layer "F.Fab")
			(hide yes)
			(effects
				(font
					(size 1.016 1.016)
					(thickness 0.1524)
				)
			)
		)
		(property "Device Type" "C603H36"
			(at 0 -4.3434 0)
			(unlocked yes)
			(layer "F.Fab")
			(hide yes)
			(effects
				(font
					(size 1.016 1.016)
					(thickness 0.1524)
				)
			)
		)
		(duplicate_pad_numbers_are_jumpers no)
		(fp_line
			(start 0.508 0)
			(end -0.508 0)
			(stroke
				(width 0.2032)
				(type default)
			)
			(layer "F.SilkS")
		)
		(fp_rect
			(start -0.5842 1.3335)
			(end 0.5842 -1.3335)
			(stroke
				(width 0)
				(type default)
			)
			(fill no)
			(layer "F.CrtYd")
		)
		(fp_rect
			(start -0.5842 1.3335)
			(end 0.5842 -1.3335)
			(stroke
				(width 0)
				(type default)
			)
			(fill no)
			(layer "F.Fab")
		)
		(pad "1" smd custom
			(at 0 -0.762)
			(size 0.2159 0.2159)
			(layers "F.Cu" "F.Mask" "F.Paste")
			(net "P3V3")
			(options
				(clearance outline)
				(anchor circle)
			)
			(primitives
				(gr_poly
					(pts
						(arc
							(start -0.3302 -0.4318)
							(mid -0.402042 -0.402042)
							(end -0.4318 -0.3302)
						)
						(arc
							(start -0.4318 0.3302)
							(mid -0.402042 0.402042)
							(end -0.3302 0.4318)
						)
						(arc
							(start 0.3302 0.4318)
							(mid 0.402042 0.402042)
							(end 0.4318 0.3302)
						)
						(arc
							(start 0.4318 -0.3302)
							(mid 0.402042 -0.402042)
							(end 0.3302 -0.4318)
						)
					)
					(width 0)
					(fill yes)
				)
			)
		)
		(pad "2" smd custom
			(at 0 0.762)
			(size 0.2159 0.2159)
			(layers "F.Cu" "F.Mask" "F.Paste")
			(net "GND")
			(options
				(clearance outline)
				(anchor circle)
			)
			(primitives
				(gr_poly
					(pts
						(arc
							(start -0.3302 -0.4318)
							(mid -0.402042 -0.402042)
							(end -0.4318 -0.3302)
						)
						(arc
							(start -0.4318 0.3302)
							(mid -0.402042 0.402042)
							(end -0.3302 0.4318)
						)
						(arc
							(start 0.3302 0.4318)
							(mid 0.402042 0.402042)
							(end 0.4318 0.3302)
						)
						(arc
							(start 0.4318 -0.3302)
							(mid 0.402042 -0.402042)
							(end 0.3302 -0.4318)
						)
					)
					(width 0)
					(fill yes)
				)
			)
		)
	)
)
